(kicad_pcb
	(version 20260206)
	(generator "pcbnew")
	(generator_version "10.0")
	(general
		(thickness 1.6)
		(legacy_teardrops no)
	)
	(paper "A4")
	(title_block
		(title "01162023_DA0F0TEBIF0_F0T_Expander_BD_F_brd_V02_OCP.brd")
		(comment 1 "Grand Teton / footprints 2709-2715 of 9728")
	)
	(layers
		(0 "F.Cu" signal "TOP")
		(4 "In1.Cu" signal "GND")
		(6 "In2.Cu" signal "VCC")
		(8 "In3.Cu" signal "VCC1")
		(10 "In4.Cu" signal "GND1")
		(12 "In5.Cu" signal "IN1")
		(14 "In6.Cu" signal "GND2")
		(16 "In7.Cu" signal "IN2")
		(18 "In8.Cu" signal "GND3")
		(20 "In9.Cu" signal "IN3")
		(22 "In10.Cu" signal "GND4")
		(24 "In11.Cu" signal "IN4")
		(26 "In12.Cu" signal "GND5")
		(28 "In13.Cu" signal "IN5")
		(30 "In14.Cu" signal "GND6")
		(32 "In15.Cu" signal "IN6")
		(34 "In16.Cu" signal "GND7")
		(2 "B.Cu" signal "BOTTOM")
		(9 "F.Adhes" user "F.Adhesive")
		(11 "B.Adhes" user "B.Adhesive")
		(13 "F.Paste" user "Package Geometry/Pastemask Top")
		(15 "B.Paste" user "Package Geometry/Pastemask Bottom")
		(5 "F.SilkS" user "Ref Des/Silkscreen Top")
		(7 "B.SilkS" user "Ref Des/Silkscreen Bottom")
		(1 "F.Mask" user "Board Geometry/Soldermask Top")
		(3 "B.Mask" user "Board Geometry/Soldermask Bottom")
		(17 "Dwgs.User" user "User.Drawings")
		(19 "Cmts.User" user "User.Comments")
		(21 "Eco1.User" user "User.Eco1")
		(23 "Eco2.User" user "User.Eco2")
		(25 "Edge.Cuts" user "Board Geometry/Outline")
		(27 "Margin" user)
		(31 "F.CrtYd" user "Package Geometry/Place Bound Top")
		(29 "B.CrtYd" user "Package Geometry/Place Bound Bottom")
		(35 "F.Fab" user "Ref Des/Assembly Top")
		(33 "B.Fab" user "Ref Des/Assembly Bottom")
	)
	(footprint ""
		(layer "F.Cu")
		(at 409.600908 -177.778918 180)
		(property "Reference" "R6434"
			(at 0 0 180)
			(layer "F.SilkS")
			(hide yes)
			(effects
				(font
					(size 1.27 1.27)
				)
			)
		)
		(property "Value" ""
			(at 0 0 180)
			(layer "F.Fab")
			(effects
				(font
					(size 1.27 1.27)
				)
			)
		)
		(duplicate_pad_numbers_are_jumpers no)
		(fp_line
			(start 0.7874 0.4064)
			(end -0.7874 0.4064)
			(stroke
				(width 0.1524)
				(type default)
			)
			(layer "F.SilkS")
		)
		(fp_line
			(start 0.7874 -0.4064)
			(end 0.7874 0.4064)
			(stroke
				(width 0.1524)
				(type default)
			)
			(layer "F.SilkS")
		)
		(fp_line
			(start -0.7874 0.4064)
			(end -0.7874 -0.4064)
			(stroke
				(width 0.1524)
				(type default)
			)
			(layer "F.SilkS")
		)
		(fp_line
			(start -0.7874 -0.4064)
			(end 0.7874 -0.4064)
			(stroke
				(width 0.1524)
				(type default)
			)
			(layer "F.SilkS")
		)
		(fp_line
			(start 0.67945 0.3048)
			(end 0.120396 0.3048)
			(stroke
				(width 0.1)
				(type default)
			)
			(layer "F.Fab")
		)
		(fp_line
			(start 0.67945 -0.3048)
			(end 0.67945 0.3048)
			(stroke
				(width 0.1)
				(type default)
			)
			(layer "F.Fab")
		)
		(fp_line
			(start 0.12065 -0.2794)
			(end 0.12065 -0.3048)
			(stroke
				(width 0.1)
				(type default)
			)
			(layer "F.Fab")
		)
		(fp_line
			(start 0.12065 -0.3048)
			(end 0.67945 -0.3048)
			(stroke
				(width 0.1)
				(type default)
			)
			(layer "F.Fab")
		)
		(fp_line
			(start 0.120396 0.3048)
			(end 0.120396 0.2794)
			(stroke
				(width 0.1)
				(type default)
			)
			(layer "F.Fab")
		)
		(fp_line
			(start 0.120396 0.2794)
			(end -0.12065 0.2794)
			(stroke
				(width 0.1)
				(type default)
			)
			(layer "F.Fab")
		)
		(fp_line
			(start -0.12065 0.3048)
			(end -0.67945 0.3048)
			(stroke
				(width 0.1)
				(type default)
			)
			(layer "F.Fab")
		)
		(fp_line
			(start -0.12065 0.2794)
			(end -0.12065 0.3048)
			(stroke
				(width 0.1)
				(type default)
			)
			(layer "F.Fab")
		)
		(fp_line
			(start -0.12065 -0.2794)
			(end 0.12065 -0.2794)
			(stroke
				(width 0.1)
				(type default)
			)
			(layer "F.Fab")
		)
		(fp_line
			(start -0.12065 -0.305054)
			(end -0.12065 -0.2794)
			(stroke
				(width 0.1)
				(type default)
			)
			(layer "F.Fab")
		)
		(fp_line
			(start -0.67945 0.3048)
			(end -0.67945 -0.305054)
			(stroke
				(width 0.1)
				(type default)
			)
			(layer "F.Fab")
		)
		(fp_line
			(start -0.67945 -0.305054)
			(end -0.12065 -0.305054)
			(stroke
				(width 0.1)
				(type default)
			)
			(layer "F.Fab")
		)
		(pad "1" smd circle
			(at -0.40005 0 180)
			(size 0 0)
			(layers "F.Cu" "F.Mask" "F.Paste")
			(net "FPGA_PEX1_MODE_SEL1_ISO")
		)
		(pad "2" smd circle
			(at 0.40005 0 180)
			(size 0 0)
			(layers "F.Cu" "F.Mask" "F.Paste")
			(net "PEX1_MODE_SEL1")
		)
	)
	(footprint ""
		(layer "F.Cu")
		(at 378.561854 -311.007252 -135)
		(property "Reference" "R1460"
			(at 0 0 225)
			(layer "F.SilkS")
			(hide yes)
			(effects
				(font
					(size 1.27 1.27)
				)
			)
		)
		(property "Value" ""
			(at 0 0 225)
			(layer "F.Fab")
			(effects
				(font
					(size 1.27 1.27)
				)
			)
		)
		(duplicate_pad_numbers_are_jumpers no)
		(fp_line
			(start 0.787389 0.406267)
			(end -0.787389 0.406267)
			(stroke
				(width 0.1524)
				(type default)
			)
			(layer "F.SilkS")
		)
		(fp_line
			(start 0.787389 -0.406267)
			(end 0.787389 0.406267)
			(stroke
				(width 0.1524)
				(type default)
			)
			(layer "F.SilkS")
		)
		(fp_line
			(start -0.787389 0.406267)
			(end -0.787389 -0.406267)
			(stroke
				(width 0.1524)
				(type default)
			)
			(layer "F.SilkS")
		)
		(fp_line
			(start -0.787389 -0.406267)
			(end 0.787389 -0.406267)
			(stroke
				(width 0.1524)
				(type default)
			)
			(layer "F.SilkS")
		)
		(fp_line
			(start 0.679446 0.30479)
			(end 0.120515 0.30479)
			(stroke
				(width 0.1)
				(type default)
			)
			(layer "F.Fab")
		)
		(fp_line
			(start 0.120515 0.30479)
			(end 0.120335 0.279466)
			(stroke
				(width 0.1)
				(type default)
			)
			(layer "F.Fab")
		)
		(fp_line
			(start 0.120335 0.279466)
			(end -0.120695 0.279466)
			(stroke
				(width 0.1)
				(type default)
			)
			(layer "F.Fab")
		)
		(fp_line
			(start 0.679446 -0.30479)
			(end 0.679446 0.30479)
			(stroke
				(width 0.1)
				(type default)
			)
			(layer "F.Fab")
		)
		(fp_line
			(start -0.120515 0.30479)
			(end -0.679446 0.30479)
			(stroke
				(width 0.1)
				(type default)
			)
			(layer "F.Fab")
		)
		(fp_line
			(start -0.120695 0.279466)
			(end -0.120515 0.30479)
			(stroke
				(width 0.1)
				(type default)
			)
			(layer "F.Fab")
		)
		(fp_line
			(start 0.120695 -0.279466)
			(end 0.120515 -0.30479)
			(stroke
				(width 0.1)
				(type default)
			)
			(layer "F.Fab")
		)
		(fp_line
			(start 0.120515 -0.30479)
			(end 0.679446 -0.30479)
			(stroke
				(width 0.1)
				(type default)
			)
			(layer "F.Fab")
		)
		(fp_line
			(start -0.679446 0.30479)
			(end -0.679446 -0.305149)
			(stroke
				(width 0.1)
				(type default)
			)
			(layer "F.Fab")
		)
		(fp_line
			(start -0.120695 -0.279466)
			(end 0.120695 -0.279466)
			(stroke
				(width 0.1)
				(type default)
			)
			(layer "F.Fab")
		)
		(fp_line
			(start -0.120695 -0.304969)
			(end -0.120695 -0.279466)
			(stroke
				(width 0.1)
				(type default)
			)
			(layer "F.Fab")
		)
		(fp_line
			(start -0.679446 -0.305149)
			(end -0.120695 -0.304969)
			(stroke
				(width 0.1)
				(type default)
			)
			(layer "F.Fab")
		)
		(pad "1" smd circle
			(at -0.40005 0 225)
			(size 0 0)
			(layers "F.Cu" "F.Mask" "F.Paste")
			(net "PU_PEX3_PAD_TRI_L")
		)
		(pad "2" smd circle
			(at 0.40005 0 225)
			(size 0 0)
			(layers "F.Cu" "F.Mask" "F.Paste")
			(net "P1V8_PEX")
		)
	)
	(footprint ""
		(layer "F.Cu")
		(at 131.27863 -111.377476 -90)
		(property "Reference" "PR7011"
			(at 0 0 270)
			(layer "F.SilkS")
			(hide yes)
			(effects
				(font
					(size 1.27 1.27)
				)
			)
		)
		(property "Value" ""
			(at 0 0 270)
			(layer "F.Fab")
			(effects
				(font
					(size 1.27 1.27)
				)
			)
		)
		(duplicate_pad_numbers_are_jumpers no)
		(fp_line
			(start -0.7874 0.4064)
			(end -0.7874 -0.4064)
			(stroke
				(width 0.1524)
				(type default)
			)
			(layer "F.SilkS")
		)
		(fp_line
			(start 0.7874 0.4064)
			(end -0.7874 0.4064)
			(stroke
				(width 0.1524)
				(type default)
			)
			(layer "F.SilkS")
		)
		(fp_line
			(start -0.7874 -0.4064)
			(end 0.7874 -0.4064)
			(stroke
				(width 0.1524)
				(type default)
			)
			(layer "F.SilkS")
		)
		(fp_line
			(start 0.7874 -0.4064)
			(end 0.7874 0.4064)
			(stroke
				(width 0.1524)
				(type default)
			)
			(layer "F.SilkS")
		)
		(fp_line
			(start -0.67945 0.3048)
			(end -0.67945 -0.305054)
			(stroke
				(width 0.1)
				(type default)
			)
			(layer "F.Fab")
		)
		(fp_line
			(start -0.12065 0.3048)
			(end -0.67945 0.3048)
			(stroke
				(width 0.1)
				(type default)
			)
			(layer "F.Fab")
		)
		(fp_line
			(start 0.120396 0.3048)
			(end 0.120396 0.2794)
			(stroke
				(width 0.1)
				(type default)
			)
			(layer "F.Fab")
		)
		(fp_line
			(start 0.67945 0.3048)
			(end 0.120396 0.3048)
			(stroke
				(width 0.1)
				(type default)
			)
			(layer "F.Fab")
		)
		(fp_line
			(start -0.12065 0.2794)
			(end -0.12065 0.3048)
			(stroke
				(width 0.1)
				(type default)
			)
			(layer "F.Fab")
		)
		(fp_line
			(start 0.120396 0.2794)
			(end -0.12065 0.2794)
			(stroke
				(width 0.1)
				(type default)
			)
			(layer "F.Fab")
		)
		(fp_line
			(start -0.12065 -0.2794)
			(end 0.12065 -0.2794)
			(stroke
				(width 0.1)
				(type default)
			)
			(layer "F.Fab")
		)
		(fp_line
			(start 0.12065 -0.2794)
			(end 0.12065 -0.3048)
			(stroke
				(width 0.1)
				(type default)
			)
			(layer "F.Fab")
		)
		(fp_line
			(start 0.12065 -0.3048)
			(end 0.67945 -0.3048)
			(stroke
				(width 0.1)
				(type default)
			)
			(layer "F.Fab")
		)
		(fp_line
			(start 0.67945 -0.3048)
			(end 0.67945 0.3048)
			(stroke
				(width 0.1)
				(type default)
			)
			(layer "F.Fab")
		)
		(fp_line
			(start -0.67945 -0.305054)
			(end -0.12065 -0.305054)
			(stroke
				(width 0.1)
				(type default)
			)
			(layer "F.Fab")
		)
		(fp_line
			(start -0.12065 -0.305054)
			(end -0.12065 -0.2794)
			(stroke
				(width 0.1)
				(type default)
			)
			(layer "F.Fab")
		)
		(pad "1" smd circle
			(at -0.40005 0 270)
			(size 0 0)
			(layers "F.Cu" "F.Mask" "F.Paste")
			(net "P3V3_NIC2_CO_MODE")
		)
		(pad "2" smd circle
			(at 0.40005 0 270)
			(size 0 0)
			(layers "F.Cu" "F.Mask" "F.Paste")
			(net "GND")
		)
	)
	(footprint ""
		(layer "F.Cu")
		(at 84.50199 -141.150848 -90)
		(property "Reference" "U14"
			(at 2.671318 0.73279 0)
			(unlocked yes)
			(layer "F.SilkS")
			(effects
				(font
					(size 0.7874 0.5842)
					(thickness 0.1524)
				)
			)
		)
		(property "Value" ""
			(at 0 0 270)
			(layer "F.Fab")
			(effects
				(font
					(size 1.27 1.27)
				)
			)
		)
		(duplicate_pad_numbers_are_jumpers no)
		(fp_line
			(start -1.949958 1.610106)
			(end -1.949958 -1.610106)
			(stroke
				(width 0.1524)
				(type default)
			)
			(layer "F.SilkS")
		)
		(fp_line
			(start 1.949958 1.610106)
			(end -1.949958 1.610106)
			(stroke
				(width 0.1524)
				(type default)
			)
			(layer "F.SilkS")
		)
		(fp_line
			(start 1.949958 -1.560068)
			(end 1.949958 1.610106)
			(stroke
				(width 0.1524)
				(type default)
			)
			(layer "F.SilkS")
		)
		(fp_line
			(start -1.949958 -1.610106)
			(end 1.949958 -1.610106)
			(stroke
				(width 0.1524)
				(type default)
			)
			(layer "F.SilkS")
		)
		(fp_line
			(start -0.750062 1.560068)
			(end -0.750062 -1.560068)
			(stroke
				(width 0.1)
				(type default)
			)
			(layer "F.Fab")
		)
		(fp_line
			(start 0.750062 1.560068)
			(end -0.750062 1.560068)
			(stroke
				(width 0.1)
				(type default)
			)
			(layer "F.Fab")
		)
		(fp_line
			(start -0.750062 -1.560068)
			(end 0.750062 -1.560068)
			(stroke
				(width 0.1)
				(type default)
			)
			(layer "F.Fab")
		)
		(fp_line
			(start 0.750062 -1.560068)
			(end 0.750062 1.560068)
			(stroke
				(width 0.1)
				(type default)
			)
			(layer "F.Fab")
		)
		(pad "D" smd rect
			(at 1.100074 0 180)
			(size 1.016 1.4224)
			(layers "F.Cu" "F.Mask" "F.Paste")
			(net "HP_NIC1_EN")
		)
		(pad "G" smd rect
			(at -1.100074 -0.94996 180)
			(size 1.016 1.4224)
			(layers "F.Cu" "F.Mask" "F.Paste")
			(net "PRSNT_NIC1_R_N")
		)
		(pad "S" smd rect
			(at -1.100074 0.94996 180)
			(size 1.016 1.4224)
			(layers "F.Cu" "F.Mask" "F.Paste")
			(net "GND")
		)
	)
	(footprint ""
		(layer "F.Cu")
		(at 358.013 -223.52 180)
		(property "Reference" "R3632"
			(at 0 0 180)
			(layer "F.SilkS")
			(hide yes)
			(effects
				(font
					(size 1.27 1.27)
				)
			)
		)
		(property "Value" ""
			(at 0 0 180)
			(layer "F.Fab")
			(effects
				(font
					(size 1.27 1.27)
				)
			)
		)
		(duplicate_pad_numbers_are_jumpers no)
		(fp_line
			(start 0.7874 0.4064)
			(end -0.7874 0.4064)
			(stroke
				(width 0.1524)
				(type default)
			)
			(layer "F.SilkS")
		)
		(fp_line
			(start 0.7874 -0.4064)
			(end 0.7874 0.4064)
			(stroke
				(width 0.1524)
				(type default)
			)
			(layer "F.SilkS")
		)
		(fp_line
			(start -0.7874 0.4064)
			(end -0.7874 -0.4064)
			(stroke
				(width 0.1524)
				(type default)
			)
			(layer "F.SilkS")
		)
		(fp_line
			(start -0.7874 -0.4064)
			(end 0.7874 -0.4064)
			(stroke
				(width 0.1524)
				(type default)
			)
			(layer "F.SilkS")
		)
		(fp_line
			(start 0.67945 0.3048)
			(end 0.120396 0.3048)
			(stroke
				(width 0.1)
				(type default)
			)
			(layer "F.Fab")
		)
		(fp_line
			(start 0.67945 -0.3048)
			(end 0.67945 0.3048)
			(stroke
				(width 0.1)
				(type default)
			)
			(layer "F.Fab")
		)
		(fp_line
			(start 0.12065 -0.2794)
			(end 0.12065 -0.3048)
			(stroke
				(width 0.1)
				(type default)
			)
			(layer "F.Fab")
		)
		(fp_line
			(start 0.12065 -0.3048)
			(end 0.67945 -0.3048)
			(stroke
				(width 0.1)
				(type default)
			)
			(layer "F.Fab")
		)
		(fp_line
			(start 0.120396 0.3048)
			(end 0.120396 0.2794)
			(stroke
				(width 0.1)
				(type default)
			)
			(layer "F.Fab")
		)
		(fp_line
			(start 0.120396 0.2794)
			(end -0.12065 0.2794)
			(stroke
				(width 0.1)
				(type default)
			)
			(layer "F.Fab")
		)
		(fp_line
			(start -0.12065 0.3048)
			(end -0.67945 0.3048)
			(stroke
				(width 0.1)
				(type default)
			)
			(layer "F.Fab")
		)
		(fp_line
			(start -0.12065 0.2794)
			(end -0.12065 0.3048)
			(stroke
				(width 0.1)
				(type default)
			)
			(layer "F.Fab")
		)
		(fp_line
			(start -0.12065 -0.2794)
			(end 0.12065 -0.2794)
			(stroke
				(width 0.1)
				(type default)
			)
			(layer "F.Fab")
		)
		(fp_line
			(start -0.12065 -0.305054)
			(end -0.12065 -0.2794)
			(stroke
				(width 0.1)
				(type default)
			)
			(layer "F.Fab")
		)
		(fp_line
			(start -0.67945 0.3048)
			(end -0.67945 -0.305054)
			(stroke
				(width 0.1)
				(type default)
			)
			(layer "F.Fab")
		)
		(fp_line
			(start -0.67945 -0.305054)
			(end -0.12065 -0.305054)
			(stroke
				(width 0.1)
				(type default)
			)
			(layer "F.Fab")
		)
		(pad "1" smd circle
			(at -0.40005 0 180)
			(size 0 0)
			(layers "F.Cu" "F.Mask" "F.Paste")
			(net "NIC3_CLK_EN_R_N")
		)
		(pad "2" smd circle
			(at 0.40005 0 180)
			(size 0 0)
			(layers "F.Cu" "F.Mask" "F.Paste")
			(net "NIC3_CLK_EN_N")
		)
	)
	(footprint ""
		(layer "F.Cu")
		(at 144.441926 -27.006296 -90)
		(property "Reference" "PR7110"
			(at 0 0 270)
			(layer "F.SilkS")
			(hide yes)
			(effects
				(font
					(size 1.27 1.27)
				)
			)
		)
		(property "Value" ""
			(at 0 0 270)
			(layer "F.Fab")
			(effects
				(font
					(size 1.27 1.27)
				)
			)
		)
		(duplicate_pad_numbers_are_jumpers no)
		(fp_line
			(start -0.7874 0.4064)
			(end -0.7874 -0.4064)
			(stroke
				(width 0.1524)
				(type default)
			)
			(layer "F.SilkS")
		)
		(fp_line
			(start 0.7874 0.4064)
			(end -0.7874 0.4064)
			(stroke
				(width 0.1524)
				(type default)
			)
			(layer "F.SilkS")
		)
		(fp_line
			(start -0.7874 -0.4064)
			(end 0.7874 -0.4064)
			(stroke
				(width 0.1524)
				(type default)
			)
			(layer "F.SilkS")
		)
		(fp_line
			(start 0.7874 -0.4064)
			(end 0.7874 0.4064)
			(stroke
				(width 0.1524)
				(type default)
			)
			(layer "F.SilkS")
		)
		(fp_line
			(start -0.67945 0.3048)
			(end -0.67945 -0.305054)
			(stroke
				(width 0.1)
				(type default)
			)
			(layer "F.Fab")
		)
		(fp_line
			(start -0.12065 0.3048)
			(end -0.67945 0.3048)
			(stroke
				(width 0.1)
				(type default)
			)
			(layer "F.Fab")
		)
		(fp_line
			(start 0.120396 0.3048)
			(end 0.120396 0.2794)
			(stroke
				(width 0.1)
				(type default)
			)
			(layer "F.Fab")
		)
		(fp_line
			(start 0.67945 0.3048)
			(end 0.120396 0.3048)
			(stroke
				(width 0.1)
				(type default)
			)
			(layer "F.Fab")
		)
		(fp_line
			(start -0.12065 0.2794)
			(end -0.12065 0.3048)
			(stroke
				(width 0.1)
				(type default)
			)
			(layer "F.Fab")
		)
		(fp_line
			(start 0.120396 0.2794)
			(end -0.12065 0.2794)
			(stroke
				(width 0.1)
				(type default)
			)
			(layer "F.Fab")
		)
		(fp_line
			(start -0.12065 -0.2794)
			(end 0.12065 -0.2794)
			(stroke
				(width 0.1)
				(type default)
			)
			(layer "F.Fab")
		)
		(fp_line
			(start 0.12065 -0.2794)
			(end 0.12065 -0.3048)
			(stroke
				(width 0.1)
				(type default)
			)
			(layer "F.Fab")
		)
		(fp_line
			(start 0.12065 -0.3048)
			(end 0.67945 -0.3048)
			(stroke
				(width 0.1)
				(type default)
			)
			(layer "F.Fab")
		)
		(fp_line
			(start 0.67945 -0.3048)
			(end 0.67945 0.3048)
			(stroke
				(width 0.1)
				(type default)
			)
			(layer "F.Fab")
		)
		(fp_line
			(start -0.67945 -0.305054)
			(end -0.12065 -0.305054)
			(stroke
				(width 0.1)
				(type default)
			)
			(layer "F.Fab")
		)
		(fp_line
			(start -0.12065 -0.305054)
			(end -0.12065 -0.2794)
			(stroke
				(width 0.1)
				(type default)
			)
			(layer "F.Fab")
		)
		(pad "1" smd circle
			(at -0.40005 0 270)
			(size 0 0)
			(layers "F.Cu" "F.Mask" "F.Paste")
			(net "P3V3_SSD5_CO_ILIMIT")
		)
		(pad "2" smd circle
			(at 0.40005 0 270)
			(size 0 0)
			(layers "F.Cu" "F.Mask" "F.Paste")
			(net "GND")
		)
	)
	(footprint ""
		(layer "F.Cu")
		(at 412.378652 -343.952322 90)
		(property "Reference" "C2441"
			(at 0 0 90)
			(layer "F.SilkS")
			(hide yes)
			(effects
				(font
					(size 1.27 1.27)
				)
			)
		)
		(property "Value" ""
			(at 0 0 90)
			(layer "F.Fab")
			(effects
				(font
					(size 1.27 1.27)
				)
			)
		)
		(duplicate_pad_numbers_are_jumpers no)
		(fp_line
			(start 0.299974 -0.150114)
			(end 0.299974 0.150114)
			(stroke
				(width 0.1)
				(type default)
			)
			(layer "F.Fab")
		)
		(fp_line
			(start -0.299974 -0.150114)
			(end 0.299974 -0.150114)
			(stroke
				(width 0.1)
				(type default)
			)
			(layer "F.Fab")
		)
		(fp_line
			(start 0.299974 0.150114)
			(end -0.299974 0.150114)
			(stroke
				(width 0.1)
				(type default)
			)
			(layer "F.Fab")
		)
		(fp_line
			(start -0.299974 0.150114)
			(end -0.299974 -0.150114)
			(stroke
				(width 0.1)
				(type default)
			)
			(layer "F.Fab")
		)
		(pad "1" smd rect
			(at -0.2667 0 90)
			(size 0.3048 0.381)
			(layers "F.Cu" "F.Mask" "F.Paste")
			(net "P5E_PEX3_STN4_TX_DP<78>")
		)
		(pad "2" smd rect
			(at 0.2667 0 90)
			(size 0.3048 0.381)
			(layers "F.Cu" "F.Mask" "F.Paste")
			(net "P5E_PEX3_STN4_TX_C_DP<78>")
		)
	)
)
